FILE_TYPE = CONNECTIVITY;
{Allegro Design Entry HDL 17.2-2016 S081 (4005846) 1/11/2022}
"PAGE_NUMBER" = 152;
0"NC";
END.
